# BASEBOARD_FAB2 (Tioga Pass) — schematic netlist excerpt (pin names and nets, part order shuffled) for the footprints in the layout excerpt that follows; sources: Cadence DE-HDL packaged netlist, KiCad conversion of Wiwynn_Tioga_Pass_MB.brd

R775  RES  0.0 5% CHIP  pkg 0402  page 244 : A = P3E_CPU0_PE1_PCH_RXN<12> ; B = P3E_CPU0_PE1_PCH_CON_RXN<12>
R6L16  RES  1.00K 1% CHIP  pkg 0402  page 98 : A = M_D_VREF ; B = GND

(kicad_pcb
	(version 20260206)
	(generator "pcbnew")
	(generator_version "10.0")
	(general
		(thickness 1.6)
		(legacy_teardrops no)
	)
	(paper "A4")
	(title_block
		(title "Wiwynn_Tioga_Pass_MB.brd")
		(comment 1 "Tioga Pass / footprints 2351-2352 of 4770")
	)
	(layers
		(0 "F.Cu" signal "TOP")
		(4 "In1.Cu" signal "L2GND")
		(6 "In2.Cu" signal "L3")
		(8 "In3.Cu" signal "L4GND")
		(10 "In4.Cu" signal "L5")
		(12 "In5.Cu" signal "L6GND")
		(14 "In6.Cu" signal "L7VCC")
		(16 "In7.Cu" signal "L8VCC")
		(18 "In8.Cu" signal "L9GND")
		(20 "In9.Cu" signal "L10")
		(22 "In10.Cu" signal "L11GND")
		(24 "In11.Cu" signal "L12")
		(26 "In12.Cu" signal "L13GND")
		(2 "B.Cu" signal "BOTTOM")
		(9 "F.Adhes" user "F.Adhesive")
		(11 "B.Adhes" user "B.Adhesive")
		(13 "F.Paste" user "Package Geometry/Pastemask Top")
		(15 "B.Paste" user "Package Geometry/Pastemask Bottom")
		(5 "F.SilkS" user "Ref Des/Silkscreen Top")
		(7 "B.SilkS" user "Ref Des/Silkscreen Bottom")
		(1 "F.Mask" user "Board Geometry/Soldermask Top")
		(3 "B.Mask" user "Board Geometry/Soldermask Bottom")
		(17 "Dwgs.User" user "User.Drawings")
		(19 "Cmts.User" user "User.Comments")
		(21 "Eco1.User" user "User.Eco1")
		(23 "Eco2.User" user "User.Eco2")
		(25 "Edge.Cuts" user "Board Geometry/Outline")
		(27 "Margin" user)
		(31 "F.CrtYd" user "Package Geometry/Place Bound Top")
		(29 "B.CrtYd" user "Package Geometry/Place Bound Bottom")
		(35 "F.Fab" user "Ref Des/Assembly Top")
		(33 "B.Fab" user "Ref Des/Assembly Bottom")
	)
	(footprint ""
		(layer "B.Cu")
		(at 194.691 -135.763)
		(property "Reference" "R6L16"
			(at 0 0 0)
			(layer "B.SilkS")
			(hide yes)
			(effects
				(font
					(size 1.27 1.27)
				)
				(justify mirror)
			)
		)
		(property "Value" ""
			(at 0 0 0)
			(layer "B.Fab")
			(effects
				(font
					(size 1.27 1.27)
				)
				(justify mirror)
			)
		)
		(duplicate_pad_numbers_are_jumpers no)
		(fp_poly
			(pts
				(xy 0.2794 -0.1016) (xy -0.2794 -0.1016) (xy -0.2794 0.9906) (xy 0.2794 0.9906)
			)
			(stroke
				(width 0)
				(type default)
			)
			(fill no)
			(layer "B.CrtYd")
		)
		(fp_line
			(start -0.2794 -0.1016)
			(end 0.2794 -0.1016)
			(stroke
				(width 0.1)
				(type default)
			)
			(layer "B.Fab")
		)
		(fp_line
			(start -0.2794 0.9906)
			(end -0.2794 -0.1016)
			(stroke
				(width 0.1)
				(type default)
			)
			(layer "B.Fab")
		)
		(fp_line
			(start 0.2794 -0.1016)
			(end 0.2794 0.9906)
			(stroke
				(width 0.1)
				(type default)
			)
			(layer "B.Fab")
		)
		(fp_line
			(start 0.2794 0.9906)
			(end -0.2794 0.9906)
			(stroke
				(width 0.1)
				(type default)
			)
			(layer "B.Fab")
		)
		(pad "1" smd rect
			(at 0 0 180)
			(size 0.508 0.508)
			(layers "B.Cu" "B.Mask" "B.Paste")
			(net "M_D_VREF")
		)
		(pad "2" smd rect
			(at 0 0.889 180)
			(size 0.508 0.508)
			(layers "B.Cu" "B.Mask" "B.Paste")
			(net "GND")
		)
		(zone
			(layer "B.Cu")
			(hatch none 0.5)
			(connect_pads
				(clearance 0)
			)
			(min_thickness 0.25)
			(keepout
				(tracks allowed)
				(vias not_allowed)
				(pads allowed)
				(copperpour not_allowed)
				(footprints allowed)
			)
			(placement
				(enabled no)
				(sheetname "")
			)
			(fill
				(thermal_gap 0.5)
				(thermal_bridge_width 0.5)
				(island_removal_mode 0)
			)
			(polygon
				(pts
					(xy 194.945 -135.509) (xy 194.437 -135.509) (xy 194.437 -135.128) (xy 194.945 -135.128)
				)
			)
		)
		(zone
			(layer "B.Cu")
			(hatch none 0.5)
			(connect_pads
				(clearance 0)
			)
			(min_thickness 0.25)
			(keepout
				(tracks not_allowed)
				(vias allowed)
				(pads allowed)
				(copperpour not_allowed)
				(footprints allowed)
			)
			(placement
				(enabled no)
				(sheetname "")
			)
			(fill
				(thermal_gap 0.5)
				(thermal_bridge_width 0.5)
				(island_removal_mode 0)
			)
			(polygon
				(pts
					(xy 194.945 -135.128) (xy 194.437 -135.128) (xy 194.437 -135.509) (xy 194.945 -135.509)
				)
			)
		)
	)
	(footprint ""
		(layer "B.Cu")
		(at 353.654614 -123.780042 -90)
		(property "Reference" "R775"
			(at 0.8382 -0.67818 270)
			(unlocked yes)
			(layer "B.SilkS")
			(effects
				(font
					(size 0.4064 0.254)
					(thickness 0.1524)
				)
				(justify left mirror)
			)
		)
		(property "Value" ""
			(at 0 0 90)
			(layer "B.Fab")
			(effects
				(font
					(size 1.27 1.27)
				)
				(justify mirror)
			)
		)
		(duplicate_pad_numbers_are_jumpers no)
		(fp_poly
			(pts
				(xy 0.2794 -0.1016) (xy -0.2794 -0.1016) (xy -0.2794 0.9906) (xy 0.2794 0.9906)
			)
			(stroke
				(width 0)
				(type default)
			)
			(fill no)
			(layer "B.CrtYd")
		)
		(fp_line
			(start -0.2794 0.9906)
			(end -0.2794 -0.1016)
			(stroke
				(width 0.1)
				(type default)
			)
			(layer "B.Fab")
		)
		(fp_line
			(start 0.2794 0.9906)
			(end -0.2794 0.9906)
			(stroke
				(width 0.1)
				(type default)
			)
			(layer "B.Fab")
		)
		(fp_line
			(start -0.2794 -0.1016)
			(end 0.2794 -0.1016)
			(stroke
				(width 0.1)
				(type default)
			)
			(layer "B.Fab")
		)
		(fp_line
			(start 0.2794 -0.1016)
			(end 0.2794 0.9906)
			(stroke
				(width 0.1)
				(type default)
			)
			(layer "B.Fab")
		)
		(pad "1" smd rect
			(at 0 0 90)
			(size 0.508 0.508)
			(layers "B.Cu" "B.Mask" "B.Paste")
			(net "P3E_CPU0_PE1_PCH_RXN<12>")
		)
		(pad "2" smd rect
			(at 0 0.889 90)
			(size 0.508 0.508)
			(layers "B.Cu" "B.Mask" "B.Paste")
			(net "P3E_CPU0_PE1_PCH_CON_RXN<12>")
		)
		(zone
			(layer "B.Cu")
			(hatch none 0.5)
			(connect_pads
				(clearance 0)
			)
			(min_thickness 0.25)
			(keepout
				(tracks not_allowed)
				(vias allowed)
				(pads allowed)
				(copperpour not_allowed)
				(footprints allowed)
			)
			(placement
				(enabled no)
				(sheetname "")
			)
			(fill
				(thermal_gap 0.5)
				(thermal_bridge_width 0.5)
				(island_removal_mode 0)
			)
			(polygon
				(pts
					(xy 353.019614 -123.526042) (xy 353.019614 -124.034042) (xy 353.400614 -124.034042) (xy 353.400614 -123.526042)
				)
			)
		)
		(zone
			(layer "B.Cu")
			(hatch none 0.5)
			(connect_pads
				(clearance 0)
			)
			(min_thickness 0.25)
			(keepout
				(tracks allowed)
				(vias not_allowed)
				(pads allowed)
				(copperpour not_allowed)
				(footprints allowed)
			)
			(placement
				(enabled no)
				(sheetname "")
			)
			(fill
				(thermal_gap 0.5)
				(thermal_bridge_width 0.5)
				(island_removal_mode 0)
			)
			(polygon
				(pts
					(xy 353.400614 -123.526042) (xy 353.400614 -124.034042) (xy 353.019614 -124.034042) (xy 353.019614 -123.526042)
				)
			)
		)
	)
)
